# S9S_MB_2U (Grand Teton) — schematic netlist excerpt (pin names and nets, part order shuffled) for the footprints in the layout excerpt that follows; sources: Cadence DE-HDL packaged netlist, KiCad conversion of 03242023_DA0F0TMBIJ0_F0T_Motherboard_J_brd_V01_OCP.brd

R3266  Q_RES  4.7K 1% CHIP  pkg 0402LF  page 166 : A = P3V3_AUX ; B = FM_P2E_MODE

X7  TP_TDR_4P_FTS  TP_TDR_4P_DIP EMPTY  pkg TH  page 309
  S1  = TDR_DIFF_85_TOP_DN
  P1  = T1_GND
  P2  = T1_GND
  S2  = TDR_DIFF_85_TOP_DP

(kicad_pcb
	(version 20260206)
	(generator "pcbnew")
	(generator_version "10.0")
	(general
		(thickness 1.6)
		(legacy_teardrops no)
	)
	(paper "A4")
	(title_block
		(title "03242023_DA0F0TMBIJ0_F0T_Motherboard_J_brd_V01_OCP.brd")
		(comment 1 "Grand Teton / footprints 2549-2550 of 6105")
	)
	(layers
		(0 "F.Cu" signal "TOP")
		(4 "In1.Cu" signal "GND")
		(6 "In2.Cu" signal "IN1")
		(8 "In3.Cu" signal "GND1")
		(10 "In4.Cu" signal "IN2")
		(12 "In5.Cu" signal "GND2")
		(14 "In6.Cu" signal "IN3")
		(16 "In7.Cu" signal "GND3")
		(18 "In8.Cu" signal "VCC")
		(20 "In9.Cu" signal "VCC1")
		(22 "In10.Cu" signal "GND4")
		(24 "In11.Cu" signal "IN4")
		(26 "In12.Cu" signal "GND5")
		(28 "In13.Cu" signal "IN5")
		(30 "In14.Cu" signal "GND6")
		(32 "In15.Cu" signal "IN6")
		(34 "In16.Cu" signal "GND7")
		(2 "B.Cu" signal "BOTTOM")
		(9 "F.Adhes" user "F.Adhesive")
		(11 "B.Adhes" user "B.Adhesive")
		(13 "F.Paste" user "Package Geometry/Pastemask Top")
		(15 "B.Paste" user "Package Geometry/Pastemask Bottom")
		(5 "F.SilkS" user "Ref Des/Silkscreen Top")
		(7 "B.SilkS" user "Ref Des/Silkscreen Bottom")
		(1 "F.Mask" user "Board Geometry/Soldermask Top")
		(3 "B.Mask" user "Board Geometry/Soldermask Bottom")
		(17 "Dwgs.User" user "User.Drawings")
		(19 "Cmts.User" user "User.Comments")
		(21 "Eco1.User" user "User.Eco1")
		(23 "Eco2.User" user "User.Eco2")
		(25 "Edge.Cuts" user "Board Geometry/Outline")
		(27 "Margin" user)
		(31 "F.CrtYd" user "Package Geometry/Place Bound Top")
		(29 "B.CrtYd" user "Package Geometry/Place Bound Bottom")
		(35 "F.Fab" user "Ref Des/Assembly Top")
		(33 "B.Fab" user "Ref Des/Assembly Bottom")
	)
	(footprint ""
		(layer "F.Cu")
		(at 527.948906 -153.205688 -90)
		(property "Reference" "X7"
			(at -1.2954 2.72923 90)
			(unlocked yes)
			(layer "F.SilkS")
			(effects
				(font
					(size 0.7874 0.5842)
					(thickness 0.1524)
				)
				(justify left)
			)
		)
		(property "Value" ""
			(at 0 0 270)
			(layer "F.Fab")
			(effects
				(font
					(size 1.27 1.27)
				)
			)
		)
		(property "Device Type" "TP_TDR_4P_FTS_MPKT4_H025P0200_I"
			(at 1.30175 1.27 0)
			(unlocked yes)
			(layer "F.Fab")
			(hide yes)
			(effects
				(font
					(size 0.635 0.4064)
					(thickness 0.1524)
				)
			)
		)
		(property "User Part Number" "TP15"
			(at 1.30175 1.27 0)
			(unlocked yes)
			(layer "Cmts.User")
			(hide yes)
			(effects
				(font
					(size 0.635 0.4064)
					(thickness 0.1524)
				)
			)
		)
		(duplicate_pad_numbers_are_jumpers no)
		(fp_line
			(start 0 3.81)
			(end 2.54 3.81)
			(stroke
				(width 0.1524)
				(type default)
			)
			(layer "F.SilkS")
		)
		(fp_line
			(start 2.54 3.81)
			(end 2.54 3.6703)
			(stroke
				(width 0.1524)
				(type default)
			)
			(layer "F.SilkS")
		)
		(fp_line
			(start 0 3.175)
			(end 0 3.81)
			(stroke
				(width 0.1524)
				(type default)
			)
			(layer "F.SilkS")
		)
		(fp_line
			(start 2.54 1.4097)
			(end 2.54 1.1303)
			(stroke
				(width 0.1524)
				(type default)
			)
			(layer "F.SilkS")
		)
		(fp_line
			(start 0 0.635)
			(end 0 1.905)
			(stroke
				(width 0.1524)
				(type default)
			)
			(layer "F.SilkS")
		)
		(fp_line
			(start 2.54 -1.1303)
			(end 2.54 -1.27)
			(stroke
				(width 0.1524)
				(type default)
			)
			(layer "F.SilkS")
		)
		(fp_line
			(start 0 -1.27)
			(end 0 -0.635)
			(stroke
				(width 0.1524)
				(type default)
			)
			(layer "F.SilkS")
		)
		(fp_line
			(start 2.54 -1.27)
			(end 0 -1.27)
			(stroke
				(width 0.1524)
				(type default)
			)
			(layer "F.SilkS")
		)
		(fp_poly
			(pts
				(xy -1.287526 0.08382) (xy -2.811526 0.84582) (xy -2.811526 -0.67818)
			)
			(stroke
				(width 0)
				(type default)
			)
			(fill yes)
			(layer "F.SilkS")
		)
		(fp_line
			(start 0 3.81)
			(end 2.54 3.81)
			(stroke
				(width 0.1)
				(type default)
			)
			(layer "F.Fab")
		)
		(fp_line
			(start 2.54 3.81)
			(end 2.54 -1.27)
			(stroke
				(width 0.1)
				(type default)
			)
			(layer "F.Fab")
		)
		(fp_line
			(start 0 -1.27)
			(end 0 3.81)
			(stroke
				(width 0.1)
				(type default)
			)
			(layer "F.Fab")
		)
		(fp_line
			(start 2.54 -1.27)
			(end 0 -1.27)
			(stroke
				(width 0.1)
				(type default)
			)
			(layer "F.Fab")
		)
		(fp_poly
			(pts
				(xy -0.761746 0) (xy -2.285746 -0.762) (xy -2.285746 0.762)
			)
			(stroke
				(width 0)
				(type default)
			)
			(fill yes)
			(layer "F.Fab")
		)
		(pad "1" thru_hole circle
			(at 0 0 270)
			(size 1.0033 1.0033)
			(drill 0.249936)
			(layers "*.Cu" "*.Mask")
			(remove_unused_layers no)
			(net "TDR_DIFF_85_TOP_DN")
			(clearance 0.10795)
			(thermal_gap 0.10795)
			(padstack
				(mode front_inner_back)
				(layer "Inner"
					(shape circle)
					(size 0.8001 0.8001)
					(clearance 0.1524)
				)
				(layer "B.Cu"
					(shape circle)
					(size 1.0033 1.0033)
					(clearance 0.10795)
				)
			)
		)
		(pad "2" thru_hole circle
			(at 2.54 0 270)
			(size 1.9939 1.9939)
			(drill 0.249936)
			(layers "*.Cu" "*.Mask")
			(remove_unused_layers no)
			(net "T1_GND")
			(clearance 0.10795)
			(thermal_gap 0.10795)
			(padstack
				(mode front_inner_back)
				(layer "Inner"
					(shape circle)
					(size 0.8001 0.8001)
					(clearance 0.1524)
				)
				(layer "B.Cu"
					(shape circle)
					(size 1.9939 1.9939)
					(clearance 0.10795)
				)
			)
		)
		(pad "3" thru_hole circle
			(at 2.54 2.54 270)
			(size 1.9939 1.9939)
			(drill 0.249936)
			(layers "*.Cu" "*.Mask")
			(remove_unused_layers no)
			(net "T1_GND")
			(clearance 0.10795)
			(thermal_gap 0.10795)
			(padstack
				(mode front_inner_back)
				(layer "Inner"
					(shape circle)
					(size 0.8001 0.8001)
					(clearance 0.1524)
				)
				(layer "B.Cu"
					(shape circle)
					(size 1.9939 1.9939)
					(clearance 0.10795)
				)
			)
		)
		(pad "4" thru_hole circle
			(at 0 2.54 270)
			(size 1.0033 1.0033)
			(drill 0.249936)
			(layers "*.Cu" "*.Mask")
			(remove_unused_layers no)
			(net "TDR_DIFF_85_TOP_DP")
			(clearance 0.10795)
			(thermal_gap 0.10795)
			(padstack
				(mode front_inner_back)
				(layer "Inner"
					(shape circle)
					(size 0.8001 0.8001)
					(clearance 0.1524)
				)
				(layer "B.Cu"
					(shape circle)
					(size 1.0033 1.0033)
					(clearance 0.10795)
				)
			)
		)
	)
	(footprint ""
		(layer "F.Cu")
		(at 15.436596 -386.103876)
		(property "Reference" "R3266"
			(at 0 0 0)
			(layer "F.SilkS")
			(hide yes)
			(effects
				(font
					(size 1.27 1.27)
				)
			)
		)
		(property "Value" ""
			(at 0 0 0)
			(layer "F.Fab")
			(effects
				(font
					(size 1.27 1.27)
				)
			)
		)
		(duplicate_pad_numbers_are_jumpers no)
		(fp_line
			(start -0.7874 -0.4064)
			(end 0.7874 -0.4064)
			(stroke
				(width 0.1524)
				(type default)
			)
			(layer "F.SilkS")
		)
		(fp_line
			(start -0.7874 0.4064)
			(end -0.7874 -0.4064)
			(stroke
				(width 0.1524)
				(type default)
			)
			(layer "F.SilkS")
		)
		(fp_line
			(start 0.7874 -0.4064)
			(end 0.7874 0.4064)
			(stroke
				(width 0.1524)
				(type default)
			)
			(layer "F.SilkS")
		)
		(fp_line
			(start 0.7874 0.4064)
			(end -0.7874 0.4064)
			(stroke
				(width 0.1524)
				(type default)
			)
			(layer "F.SilkS")
		)
		(fp_line
			(start -0.67945 -0.305054)
			(end -0.12065 -0.305054)
			(stroke
				(width 0.1)
				(type default)
			)
			(layer "F.Fab")
		)
		(fp_line
			(start -0.67945 0.3048)
			(end -0.67945 -0.305054)
			(stroke
				(width 0.1)
				(type default)
			)
			(layer "F.Fab")
		)
		(fp_line
			(start -0.12065 -0.305054)
			(end -0.12065 -0.2794)
			(stroke
				(width 0.1)
				(type default)
			)
			(layer "F.Fab")
		)
		(fp_line
			(start -0.12065 -0.2794)
			(end 0.12065 -0.2794)
			(stroke
				(width 0.1)
				(type default)
			)
			(layer "F.Fab")
		)
		(fp_line
			(start -0.12065 0.2794)
			(end -0.12065 0.3048)
			(stroke
				(width 0.1)
				(type default)
			)
			(layer "F.Fab")
		)
		(fp_line
			(start -0.12065 0.3048)
			(end -0.67945 0.3048)
			(stroke
				(width 0.1)
				(type default)
			)
			(layer "F.Fab")
		)
		(fp_line
			(start 0.120396 0.2794)
			(end -0.12065 0.2794)
			(stroke
				(width 0.1)
				(type default)
			)
			(layer "F.Fab")
		)
		(fp_line
			(start 0.120396 0.3048)
			(end 0.120396 0.2794)
			(stroke
				(width 0.1)
				(type default)
			)
			(layer "F.Fab")
		)
		(fp_line
			(start 0.12065 -0.3048)
			(end 0.67945 -0.3048)
			(stroke
				(width 0.1)
				(type default)
			)
			(layer "F.Fab")
		)
		(fp_line
			(start 0.12065 -0.2794)
			(end 0.12065 -0.3048)
			(stroke
				(width 0.1)
				(type default)
			)
			(layer "F.Fab")
		)
		(fp_line
			(start 0.67945 -0.3048)
			(end 0.67945 0.3048)
			(stroke
				(width 0.1)
				(type default)
			)
			(layer "F.Fab")
		)
		(fp_line
			(start 0.67945 0.3048)
			(end 0.120396 0.3048)
			(stroke
				(width 0.1)
				(type default)
			)
			(layer "F.Fab")
		)
		(pad "1" smd circle
			(at -0.40005 0)
			(size 0 0)
			(layers "F.Cu" "F.Mask" "F.Paste")
			(net "P3V3_AUX")
		)
		(pad "2" smd circle
			(at 0.40005 0)
			(size 0 0)
			(layers "F.Cu" "F.Mask" "F.Paste")
			(net "FM_P2E_MODE")
		)
	)
)
